FILE_TYPE = MACRO_DRAWING;
SET COLOR_WIRE YELLOW;
SET COLOR_PROP MONO;
SET COLOR_DOT WHITE;
SET COLOR_ARC YELLOW;
SET COLOR_BODY GREEN;
SET COLOR_NOTE MONO;
SET PROP_DISPLAY VALUE;
SET PAGE_NUMBER P135;
FORCEADD P3V3_STBY..1
(200 2525);
FORCEPROP 3 LASTPIN (200 2475) SIG_NAME P3V3_STBY\g
J 0
(210 2485);
DISPLAY 0.659574 (210 2485);
PAINT MONO (210 2485);
DISPLAY INVISIBLE (210 2485);
FORCEPROP 1 LAST PATH I106
J 0
(245 2527);
DISPLAY 0.340426 (245 2527);
PAINT GREEN (245 2527);
DISPLAY INVISIBLE (245 2527);
FORCEPROP 1 LAST BODY_TYPE PLUMBING
J 0
(155 2482);
DISPLAY 0.340426 (155 2482);
PAINT GREEN (155 2482);
DISPLAY INVISIBLE (155 2482);
FORCEPROP 2 LAST CDS_LIB mstr_symbols
J 0
(200 2525);
PAINT MONO (200 2525);
DISPLAY INVISIBLE (200 2525);
FORCEPROP 1 LAST SIZE 1B
J 0
(245 2547);
DISPLAY 0.340426 (245 2547);
PAINT GREEN (245 2547);
DISPLAY INVISIBLE (245 2547);
FORCEPROP 1 LAST HDL_POWER P3V3_STBY
J 0
(-100 2400);
DISPLAY 0.872340 (-100 2400);
PAINT ORANGE (-100 2400);
DISPLAY INVISIBLE (-100 2400);
FORCEPROP 1 LAST VOLTAGE 3.3V
J 0
(155 2482);
DISPLAY 0.340426 (155 2482);
PAINT SKYBLUE (155 2482);
DISPLAY INVISIBLE (155 2482);
FORCEADD RES..2
(200 2225);
FORCEPROP 1 LASTPIN (200 2125) $PN 2
J 0
(205 2135);
DISPLAY 0.617021 (205 2135);
PAINT ORANGE (205 2135);
FORCEPROP 1 LASTPIN (200 2325) $PN 1
J 0
(205 2287);
DISPLAY 0.617021 (205 2287);
PAINT ORANGE (205 2287);
FORCEPROP 1 LAST WATTAGE 1/16W
J 0
(240 2200);
DISPLAY 0.617021 (240 2200);
PAINT SKYBLUE (240 2200);
FORCEPROP 1 LAST MATERIAL CHIP
J 0
(240 2150);
DISPLAY 0.617021 (240 2150);
PAINT SKYBLUE (240 2150);
FORCEPROP 1 LAST PACK_TYPE 0402
J 0
(240 2050);
DISPLAY 0.617021 (240 2050);
PAINT SKYBLUE (240 2050);
FORCEPROP 1 LAST TOLERANCE 1%
J 0
(245 2250);
DISPLAY 0.617021 (245 2250);
PAINT SKYBLUE (245 2250);
FORCEPROP 1 LAST VALUE 10.0K
J 0
(245 2300);
DISPLAY 0.617021 (245 2300);
PAINT SKYBLUE (245 2300);
FORCEPROP 1 LAST PART_NUMBER G21796-016
J 0
(240 2100);
DISPLAY 0.617021 (240 2100);
PAINT BLUE (240 2100);
FORCEPROP 1 LAST LOCATION R2P19
J 0
(245 2350);
DISPLAY 0.617021 (245 2350);
PAINT AQUA (245 2350);
FORCEPROP 2 LAST CDS_LIB mstr_discrete
J 0
(200 2225);
PAINT MONO (200 2225);
DISPLAY INVISIBLE (200 2225);
FORCEPROP 1 LAST PATH I107
J 0
(250 2400);
DISPLAY 0.978723 (250 2400);
PAINT WHITE (250 2400);
DISPLAY INVISIBLE (250 2400);
FORCEPROP 2 LAST SEC 1
J 0
(250 2450);
PAINT MONO (250 2450);
DISPLAY INVISIBLE (250 2450);
FORCEPROP 0 LAST BOM_COST CPLD
J 0
(250 2450);
DISPLAY 1.021277 (250 2450);
PAINT ORANGE (250 2450);
DISPLAY INVISIBLE (250 2450);
FORCEPROP 2 LAST SEC_TYPE 0402
J 0
(250 2450);
DISPLAY 1.021277 (250 2450);
PAINT ORANGE (250 2450);
DISPLAY INVISIBLE (250 2450);
FORCEPROP 0 LAST ROOM CPLD
J 0
(250 2450);
DISPLAY 1.021277 (250 2450);
PAINT ORANGE (250 2450);
DISPLAY INVISIBLE (250 2450);
FORCEADD OFFPAGE..2
(675 1950);
FORCEPROP 2 LAST $XR0 120 
J 0
(864 1950);
DISPLAY 0.638298 (864 1950);
PAINT MONO (864 1950);
FORCEPROP 2 LAST $XR1 190 
J 0
(984 1950);
DISPLAY 0.638298 (984 1950);
PAINT MONO (984 1950);
FORCEPROP 2 LAST ROOM WBG_HEADERS_BIOS
J 0
(450 2025);
PAINT ORANGE (450 2025);
DISPLAY INVISIBLE (450 2025);
FORCEPROP 2 LAST PATH I108
J 0
(1000 2000);
DISPLAY 1.021277 (1000 2000);
PAINT ORANGE (1000 2000);
DISPLAY INVISIBLE (1000 2000);
FORCEPROP 1 LAST OFFPAGE TRUE
J 0
(1000 1825);
PAINT GREEN (1000 1825);
DISPLAY INVISIBLE (1000 1825);
FORCEPROP 2 LAST BOM_COST SB
J 0
(875 2000);
PAINT ORANGE (875 2000);
DISPLAY INVISIBLE (875 2000);
FORCEPROP 2 LAST CDS_LIB mstr_standard
J 0
(675 1950);
PAINT MONO (675 1950);
DISPLAY INVISIBLE (675 1950);
FORCEPROP 1 LAST COMMENT_BODY TRUE
J 0
(630 1855);
DISPLAY 0.978723 (630 1855);
PAINT GREEN (630 1855);
DISPLAY INVISIBLE (630 1855);
FORCEADD OFFPAGE..2
(675 1800);
FORCEPROP 2 LAST $XR0 190 
J 0
(864 1800);
DISPLAY 0.638298 (864 1800);
PAINT MONO (864 1800);
FORCEPROP 2 LAST PATH I109
J 0
(875 1850);
DISPLAY 1.021277 (875 1850);
PAINT ORANGE (875 1850);
DISPLAY INVISIBLE (875 1850);
FORCEPROP 1 LAST OFFPAGE TRUE
J 0
(1000 1675);
DISPLAY 0.872340 (1000 1675);
PAINT GREEN (1000 1675);
DISPLAY INVISIBLE (1000 1675);
FORCEPROP 2 LAST CDS_LIB mstr_standard
J 0
(675 1800);
PAINT ORANGE (675 1800);
DISPLAY INVISIBLE (675 1800);
FORCEPROP 1 LAST COMMENT_BODY TRUE
J 0
(630 1705);
DISPLAY 0.872340 (630 1705);
PAINT GREEN (630 1705);
DISPLAY INVISIBLE (630 1705);
FORCEADD OFFPAGE..2
(-1500 4525);
FORCEPROP 2 LAST $XR0 119 
J 0
(-1311 4525);
DISPLAY 0.638298 (-1311 4525);
PAINT MONO (-1311 4525);
FORCEPROP 2 LASTPIN (-1550 4525) SIG_NAME FM_QAT_EN_N
J 2
(-1560 4535);
DISPLAY 0.617021 (-1560 4535);
PAINT ORANGE (-1560 4535);
FORCEPROP 2 LAST PATH I110
J 0
(-1300 4575);
DISPLAY 1.021277 (-1300 4575);
PAINT ORANGE (-1300 4575);
DISPLAY INVISIBLE (-1300 4575);
FORCEPROP 1 LAST OFFPAGE TRUE
J 0
(-1175 4400);
DISPLAY 0.872340 (-1175 4400);
PAINT GREEN (-1175 4400);
DISPLAY INVISIBLE (-1175 4400);
FORCEPROP 2 LAST CDS_LIB mstr_standard
J 0
(-1500 4525);
PAINT ORANGE (-1500 4525);
DISPLAY INVISIBLE (-1500 4525);
FORCEPROP 1 LAST COMMENT_BODY TRUE
J 0
(-1545 4430);
DISPLAY 0.872340 (-1545 4430);
PAINT GREEN (-1545 4430);
DISPLAY INVISIBLE (-1545 4430);
FORCEADD P3V3_STBY..1
(-2150 5025);
FORCEPROP 3 LASTPIN (-2150 4975) SIG_NAME P3V3_STBY\g
J 0
(-2140 4985);
DISPLAY 0.659574 (-2140 4985);
PAINT MONO (-2140 4985);
DISPLAY INVISIBLE (-2140 4985);
FORCEPROP 1 LAST BODY_TYPE PLUMBING
J 0
(-2195 4982);
DISPLAY 0.340426 (-2195 4982);
PAINT GREEN (-2195 4982);
DISPLAY INVISIBLE (-2195 4982);
FORCEPROP 1 LAST PATH I111
J 0
(-2105 5027);
DISPLAY 0.340426 (-2105 5027);
PAINT GREEN (-2105 5027);
DISPLAY INVISIBLE (-2105 5027);
FORCEPROP 1 LAST SIZE 1B
J 0
(-2105 5047);
DISPLAY 0.340426 (-2105 5047);
PAINT GREEN (-2105 5047);
DISPLAY INVISIBLE (-2105 5047);
FORCEPROP 2 LAST CDS_LIB mstr_symbols
J 0
(-2150 5025);
PAINT ORANGE (-2150 5025);
DISPLAY INVISIBLE (-2150 5025);
FORCEPROP 1 LAST HDL_POWER P3V3_STBY
J 0
(-2450 4900);
DISPLAY 0.872340 (-2450 4900);
PAINT ORANGE (-2450 4900);
DISPLAY INVISIBLE (-2450 4900);
FORCEPROP 1 LAST VOLTAGE 3.3V
J 0
(-2195 4982);
DISPLAY 0.340426 (-2195 4982);
PAINT SKYBLUE (-2195 4982);
DISPLAY INVISIBLE (-2195 4982);
FORCEADD RES..2
(-2150 4775);
FORCEPROP 1 LASTPIN (-2150 4875) $PN 1
J 0
(-2145 4837);
DISPLAY 0.617021 (-2145 4837);
PAINT ORANGE (-2145 4837);
FORCEPROP 1 LASTPIN (-2150 4675) $PN 2
J 0
(-2145 4685);
DISPLAY 0.617021 (-2145 4685);
PAINT ORANGE (-2145 4685);
FORCEPROP 1 LAST WATTAGE 1/16W
J 0
(-2110 4750);
DISPLAY 0.617021 (-2110 4750);
PAINT SKYBLUE (-2110 4750);
FORCEPROP 1 LAST MATERIAL CHIP
J 0
(-2110 4700);
DISPLAY 0.617021 (-2110 4700);
PAINT SKYBLUE (-2110 4700);
FORCEPROP 1 LAST PACK_TYPE 0402
J 0
(-2110 4600);
DISPLAY 0.617021 (-2110 4600);
PAINT SKYBLUE (-2110 4600);
FORCEPROP 1 LAST TOLERANCE 1%
J 0
(-2105 4800);
DISPLAY 0.617021 (-2105 4800);
PAINT SKYBLUE (-2105 4800);
FORCEPROP 1 LAST VALUE 10.0K
J 0
(-2105 4850);
DISPLAY 0.617021 (-2105 4850);
PAINT SKYBLUE (-2105 4850);
FORCEPROP 1 LAST PART_NUMBER G21796-016
J 0
(-2110 4650);
DISPLAY 0.617021 (-2110 4650);
PAINT BLUE (-2110 4650);
FORCEPROP 1 LAST LOCATION R2N23
J 0
(-2105 4900);
DISPLAY 0.617021 (-2105 4900);
PAINT AQUA (-2105 4900);
FORCEPROP 2 LAST CDS_LIB mstr_discrete
J 0
(-2150 4775);
PAINT ORANGE (-2150 4775);
DISPLAY INVISIBLE (-2150 4775);
FORCEPROP 1 LAST PATH I112
J 0
(-2100 4950);
DISPLAY 0.978723 (-2100 4950);
PAINT WHITE (-2100 4950);
DISPLAY INVISIBLE (-2100 4950);
FORCEPROP 2 LAST CDS_LOCATION R2N23
J 0
(-2105 4900);
DISPLAY 0.617021 (-2105 4900);
PAINT AQUA (-2105 4900);
DISPLAY INVISIBLE (-2105 4900);
FORCEPROP 2 LAST $SEC 1
J 0
(-2100 5000);
DISPLAY 0.680851 (-2100 5000);
PAINT MONO (-2100 5000);
DISPLAY INVISIBLE (-2100 5000);
FORCEPROP 2 LAST CDS_SEC 1
J 0
(-2100 5000);
PAINT MONO (-2100 5000);
DISPLAY INVISIBLE (-2100 5000);
FORCEPROP 2 LAST ROOM SB
J 0
(-2100 4950);
PAINT MONO (-2100 4950);
DISPLAY INVISIBLE (-2100 4950);
FORCEADD RES..2
(-2150 4325);
FORCEPROP 1 LASTPIN (-2150 4225) $PN 2
J 0
(-2145 4235);
DISPLAY 0.617021 (-2145 4235);
PAINT ORANGE (-2145 4235);
FORCEPROP 1 LASTPIN (-2150 4425) $PN 1
J 0
(-2145 4387);
DISPLAY 0.617021 (-2145 4387);
PAINT ORANGE (-2145 4387);
FORCEPROP 1 LAST WATTAGE 1/16W
J 0
(-2110 4300);
DISPLAY 0.617021 (-2110 4300);
PAINT SKYBLUE (-2110 4300);
FORCEPROP 1 LAST PACK_TYPE 0402
J 0
(-2110 4150);
DISPLAY 0.617021 (-2110 4150);
PAINT SKYBLUE (-2110 4150);
FORCEPROP 1 LAST TOLERANCE 1%
J 0
(-2105 4350);
DISPLAY 0.617021 (-2105 4350);
PAINT SKYBLUE (-2105 4350);
FORCEPROP 1 LAST VALUE 1.00K
J 0
(-2105 4400);
DISPLAY 0.617021 (-2105 4400);
PAINT SKYBLUE (-2105 4400);
FORCEPROP 1 LAST PART_NUMBER G21796-026
J 0
(-2110 4200);
DISPLAY 0.617021 (-2110 4200);
PAINT BLUE (-2110 4200);
FORCEPROP 1 LAST LOCATION R2N24
J 0
(-2105 4450);
DISPLAY 0.617021 (-2105 4450);
PAINT AQUA (-2105 4450);
FORCEPROP 1 LAST MATERIAL EMPTY
J 0
(-2110 4250);
DISPLAY 0.617021 (-2110 4250);
PAINT RED (-2110 4250);
FORCEPROP 2 LAST CDS_LIB mstr_discrete
J 0
(-2150 4325);
PAINT ORANGE (-2150 4325);
DISPLAY INVISIBLE (-2150 4325);
FORCEPROP 2 LAST CDS_LOCATION R2N24
J 0
(-2105 4450);
DISPLAY 0.617021 (-2105 4450);
PAINT AQUA (-2105 4450);
DISPLAY INVISIBLE (-2105 4450);
FORCEPROP 1 LAST PATH I113
J 0
(-2100 4500);
DISPLAY 0.978723 (-2100 4500);
PAINT WHITE (-2100 4500);
DISPLAY INVISIBLE (-2100 4500);
FORCEPROP 2 LAST SEC 1
J 0
(-2100 4550);
DISPLAY 0.680851 (-2100 4550);
PAINT MONO (-2100 4550);
DISPLAY INVISIBLE (-2100 4550);
FORCEPROP 2 LAST SEC_TYPE 0402
J 0
(-2100 4550);
DISPLAY 1.021277 (-2100 4550);
PAINT ORANGE (-2100 4550);
DISPLAY INVISIBLE (-2100 4550);
FORCEPROP 2 LAST ROOM SB
J 0
(-2100 4500);
PAINT MONO (-2100 4500);
DISPLAY INVISIBLE (-2100 4500);
FORCEADD GND..1
(-2150 4125);
FORCEPROP 3 LASTPIN (-2150 4175) SIG_NAME GND\g
J 0
(-2140 4185);
DISPLAY 0.659574 (-2140 4185);
PAINT MONO (-2140 4185);
DISPLAY INVISIBLE (-2140 4185);
FORCEPROP 1 LAST SIZE 1B
J 0
(-2075 4075);
DISPLAY 0.872340 (-2075 4075);
PAINT AQUA (-2075 4075);
DISPLAY INVISIBLE (-2075 4075);
FORCEPROP 1 LAST BODY_TYPE PLUMBING
J 0
(-2195 4082);
DISPLAY 0.340426 (-2195 4082);
PAINT GREEN (-2195 4082);
DISPLAY INVISIBLE (-2195 4082);
FORCEPROP 1 LAST PATH I114
J 0
(-2075 4125);
DISPLAY 0.872340 (-2075 4125);
PAINT AQUA (-2075 4125);
DISPLAY INVISIBLE (-2075 4125);
FORCEPROP 2 LAST CDS_LIB mstr_symbols
J 0
(-2150 4125);
PAINT ORANGE (-2150 4125);
DISPLAY INVISIBLE (-2150 4125);
FORCEPROP 1 LAST HDL_POWER GND
J 0
(-2150 4275);
DISPLAY 0.872340 (-2150 4275);
PAINT GREEN (-2150 4275);
DISPLAY INVISIBLE (-2150 4275);
FORCEPROP 1 LAST VOLTAGE 0.0V
J 0
(-2195 4082);
DISPLAY 0.340426 (-2195 4082);
PAINT SKYBLUE (-2195 4082);
DISPLAY INVISIBLE (-2195 4082);
FORCEADD OFFPAGE..3
(-3025 4500);
FORCEPROP 2 LAST $XR0 119 
J 0
(-2811 4500);
DISPLAY 0.638298 (-2811 4500);
PAINT MONO (-2811 4500);
FORCEPROP 1 LAST OFFPAGE TRUE
J 0
(-2700 4375);
DISPLAY 0.872340 (-2700 4375);
PAINT GREEN (-2700 4375);
DISPLAY INVISIBLE (-2700 4375);
FORCEPROP 2 LAST PATH I115
J 0
(-2800 4550);
DISPLAY 1.021277 (-2800 4550);
PAINT ORANGE (-2800 4550);
DISPLAY INVISIBLE (-2800 4550);
FORCEPROP 2 LAST ROOM WBG_HEADERS_BIOS
J 0
(-2825 4550);
PAINT MONO (-2825 4550);
DISPLAY INVISIBLE (-2825 4550);
FORCEPROP 2 LAST BOM_COST SB
J 0
(-2825 4550);
PAINT MONO (-2825 4550);
DISPLAY INVISIBLE (-2825 4550);
FORCEPROP 2 LAST CDS_LIB mstr_standard
J 0
(-3025 4500);
PAINT MONO (-3025 4500);
DISPLAY INVISIBLE (-3025 4500);
FORCEPROP 1 LAST COMMENT_BODY TRUE
J 0
(-3075 4400);
DISPLAY 0.872340 (-3075 4400);
PAINT GREEN (-3075 4400);
DISPLAY INVISIBLE (-3075 4400);
FORCEADD P3V3_STBY..1
(-3875 5150);
FORCEPROP 3 LASTPIN (-3875 5100) SIG_NAME P3V3_STBY\g
J 0
(-3865 5110);
DISPLAY 0.659574 (-3865 5110);
PAINT MONO (-3865 5110);
DISPLAY INVISIBLE (-3865 5110);
FORCEPROP 1 LAST BODY_TYPE PLUMBING
J 0
(-3920 5107);
DISPLAY 0.340426 (-3920 5107);
PAINT GREEN (-3920 5107);
DISPLAY INVISIBLE (-3920 5107);
FORCEPROP 1 LAST PATH I116
J 0
(-3830 5152);
DISPLAY 0.340426 (-3830 5152);
PAINT GREEN (-3830 5152);
DISPLAY INVISIBLE (-3830 5152);
FORCEPROP 2 LAST CDS_LIB mstr_symbols
J 0
(-3875 5150);
PAINT ORANGE (-3875 5150);
DISPLAY INVISIBLE (-3875 5150);
FORCEPROP 1 LAST SIZE 1B
J 0
(-3830 5172);
DISPLAY 0.340426 (-3830 5172);
PAINT GREEN (-3830 5172);
DISPLAY INVISIBLE (-3830 5172);
FORCEPROP 1 LAST HDL_POWER P3V3_STBY
J 0
(-4175 5025);
DISPLAY 0.872340 (-4175 5025);
PAINT ORANGE (-4175 5025);
DISPLAY INVISIBLE (-4175 5025);
FORCEPROP 1 LAST VOLTAGE 3.3V
J 0
(-3920 5107);
DISPLAY 0.340426 (-3920 5107);
PAINT SKYBLUE (-3920 5107);
DISPLAY INVISIBLE (-3920 5107);
FORCEADD RES..1
R 1
(-3875 4900);
FORCEPROP 1 LASTPIN (-3875 4800) $PN 1
J 0
(-3912 4812);
DISPLAY 0.617021 (-3912 4812);
PAINT MONO (-3912 4812);
FORCEPROP 1 LASTPIN (-3875 5000) $PN 2
J 0
(-3912 4962);
DISPLAY 0.617021 (-3912 4962);
PAINT MONO (-3912 4962);
FORCEPROP 1 LAST WATTAGE 1/16W
J 0
(-3850 4825);
DISPLAY 0.617021 (-3850 4825);
PAINT SKYBLUE (-3850 4825);
FORCEPROP 1 LAST MATERIAL CHIP
J 0
(-3850 4775);
DISPLAY 0.617021 (-3850 4775);
PAINT SKYBLUE (-3850 4775);
FORCEPROP 1 LAST PACK_TYPE 0402
J 0
(-3850 4650);
DISPLAY 0.617021 (-3850 4650);
PAINT SKYBLUE (-3850 4650);
FORCEPROP 1 LAST TOLERANCE 1%
J 0
(-3850 4875);
DISPLAY 0.617021 (-3850 4875);
PAINT SKYBLUE (-3850 4875);
FORCEPROP 1 LAST VALUE 2.21K
J 0
(-3850 4925);
DISPLAY 0.617021 (-3850 4925);
PAINT SKYBLUE (-3850 4925);
FORCEPROP 1 LAST PART_NUMBER G21796-112
J 0
(-3850 4725);
DISPLAY 0.617021 (-3850 4725);
PAINT BLUE (-3850 4725);
FORCEPROP 1 LAST LOCATION R9A12
J 0
(-3850 5000);
DISPLAY 0.617021 (-3850 5000);
PAINT AQUA (-3850 5000);
FORCEPROP 1 LAST PATH I117
R 1
J 0
(-4025 4850);
DISPLAY 0.978723 (-4025 4850);
PAINT WHITE (-4025 4850);
DISPLAY INVISIBLE (-4025 4850);
FORCEPROP 2 LAST CDS_LIB mstr_discrete
R 1
J 0
(-3875 4900);
PAINT MONO (-3875 4900);
DISPLAY INVISIBLE (-3875 4900);
FORCEPROP 2 LAST BOM_COST SB
J 0
(-3850 5050);
PAINT MONO (-3850 5050);
DISPLAY INVISIBLE (-3850 5050);
FORCEPROP 2 LAST CDS_SEC 1
J 0
(-3850 5050);
DISPLAY 1.404255 (-3850 5050);
PAINT ORANGE (-3850 5050);
DISPLAY INVISIBLE (-3850 5050);
FORCEPROP 2 LAST $SEC 1
J 0
(-3850 5050);
DISPLAY 0.936170 (-3850 5050);
PAINT MONO (-3850 5050);
DISPLAY INVISIBLE (-3850 5050);
FORCEPROP 2 LAST CDS_LOCATION R9A12
J 0
(-3850 5000);
DISPLAY 0.617021 (-3850 5000);
PAINT AQUA (-3850 5000);
DISPLAY INVISIBLE (-3850 5000);
FORCEPROP 2 LAST ROOM SB
J 0
(-3850 5050);
PAINT MONO (-3850 5050);
DISPLAY INVISIBLE (-3850 5050);
FORCEADD RES..1
(-3650 4500);
FORCEPROP 1 LASTPIN (-3750 4500) $PN 1
J 0
(-3738 4512);
DISPLAY 0.617021 (-3738 4512);
PAINT MONO (-3738 4512);
FORCEPROP 1 LASTPIN (-3550 4500) $PN 2
J 0
(-3588 4512);
DISPLAY 0.617021 (-3588 4512);
PAINT MONO (-3588 4512);
FORCEPROP 1 LAST WATTAGE 1/16W
J 2
(-3675 4350);
DISPLAY 0.617021 (-3675 4350);
PAINT SKYBLUE (-3675 4350);
FORCEPROP 1 LAST MATERIAL CHIP
J 0
(-3650 4350);
DISPLAY 0.617021 (-3650 4350);
PAINT SKYBLUE (-3650 4350);
FORCEPROP 1 LAST PACK_TYPE 0402
J 0
(-3400 4350);
DISPLAY 0.617021 (-3400 4350);
PAINT SKYBLUE (-3400 4350);
FORCEPROP 1 LAST TOLERANCE 1%
J 0
(-3650 4400);
DISPLAY 0.617021 (-3650 4400);
PAINT SKYBLUE (-3650 4400);
FORCEPROP 1 LAST VALUE 33.2
J 2
(-3675 4400);
DISPLAY 0.617021 (-3675 4400);
PAINT SKYBLUE (-3675 4400);
FORCEPROP 1 LAST PART_NUMBER G21796-074
J 0
(-3900 4275);
DISPLAY 0.617021 (-3900 4275);
PAINT BLUE (-3900 4275);
FORCEPROP 1 LAST LOCATION R9A13
J 0
(-3700 4550);
DISPLAY 0.617021 (-3700 4550);
PAINT AQUA (-3700 4550);
FORCEPROP 2 LAST CDS_LIB mstr_discrete
J 0
(-3650 4500);
PAINT MONO (-3650 4500);
DISPLAY INVISIBLE (-3650 4500);
FORCEPROP 2 LAST CDS_LOCATION R9A13
J 0
(-3700 4550);
DISPLAY 0.617021 (-3700 4550);
PAINT AQUA (-3700 4550);
DISPLAY INVISIBLE (-3700 4550);
FORCEPROP 2 LAST BOM_COST SB
J 0
(-3700 4600);
PAINT MONO (-3700 4600);
DISPLAY INVISIBLE (-3700 4600);
FORCEPROP 2 LAST CDS_SEC 1
J 0
(-3700 4700);
DISPLAY 1.404255 (-3700 4700);
PAINT ORANGE (-3700 4700);
DISPLAY INVISIBLE (-3700 4700);
FORCEPROP 2 LAST $SEC 1
J 0
(-3700 4700);
DISPLAY 0.936170 (-3700 4700);
PAINT MONO (-3700 4700);
DISPLAY INVISIBLE (-3700 4700);
FORCEPROP 1 LAST PATH I118
J 0
(-3700 4650);
DISPLAY 0.978723 (-3700 4650);
PAINT WHITE (-3700 4650);
DISPLAY INVISIBLE (-3700 4650);
FORCEPROP 2 LAST ROOM SB
J 0
(-3700 4600);
PAINT MONO (-3700 4600);
DISPLAY INVISIBLE (-3700 4600);
FORCEADD P3V3_STBY..1
(-225 2525);
FORCEPROP 3 LASTPIN (-225 2475) SIG_NAME P3V3_STBY\g
J 0
(-215 2485);
DISPLAY 0.659574 (-215 2485);
PAINT MONO (-215 2485);
DISPLAY INVISIBLE (-215 2485);
FORCEPROP 1 LAST BODY_TYPE PLUMBING
J 0
(-270 2482);
DISPLAY 0.340426 (-270 2482);
PAINT GREEN (-270 2482);
DISPLAY INVISIBLE (-270 2482);
FORCEPROP 1 LAST PATH I119
J 0
(-180 2527);
DISPLAY 0.340426 (-180 2527);
PAINT GREEN (-180 2527);
DISPLAY INVISIBLE (-180 2527);
FORCEPROP 1 LAST SIZE 1B
J 0
(-180 2547);
DISPLAY 0.340426 (-180 2547);
PAINT GREEN (-180 2547);
DISPLAY INVISIBLE (-180 2547);
FORCEPROP 2 LAST CDS_LIB mstr_symbols
J 0
(-225 2525);
PAINT MONO (-225 2525);
DISPLAY INVISIBLE (-225 2525);
FORCEPROP 1 LAST HDL_POWER P3V3_STBY
J 0
(-525 2400);
DISPLAY 0.872340 (-525 2400);
PAINT ORANGE (-525 2400);
DISPLAY INVISIBLE (-525 2400);
FORCEPROP 1 LAST VOLTAGE 3.3V
J 0
(-270 2482);
DISPLAY 0.340426 (-270 2482);
PAINT SKYBLUE (-270 2482);
DISPLAY INVISIBLE (-270 2482);
FORCEADD RES..2
(-225 2250);
FORCEPROP 1 LASTPIN (-225 2150) $PN 2
J 0
(-220 2160);
DISPLAY 0.617021 (-220 2160);
PAINT ORANGE (-220 2160);
FORCEPROP 1 LASTPIN (-225 2350) $PN 1
J 0
(-220 2312);
DISPLAY 0.617021 (-220 2312);
PAINT ORANGE (-220 2312);
FORCEPROP 1 LAST WATTAGE 1/16W
J 0
(-185 2225);
DISPLAY 0.617021 (-185 2225);
PAINT SKYBLUE (-185 2225);
FORCEPROP 1 LAST MATERIAL CHIP
J 0
(-185 2175);
DISPLAY 0.617021 (-185 2175);
PAINT SKYBLUE (-185 2175);
FORCEPROP 1 LAST PACK_TYPE 0402
J 0
(-185 2075);
DISPLAY 0.617021 (-185 2075);
PAINT SKYBLUE (-185 2075);
FORCEPROP 1 LAST TOLERANCE 1%
J 0
(-180 2275);
DISPLAY 0.617021 (-180 2275);
PAINT SKYBLUE (-180 2275);
FORCEPROP 1 LAST VALUE 1.00K
J 0
(-180 2325);
DISPLAY 0.617021 (-180 2325);
PAINT SKYBLUE (-180 2325);
FORCEPROP 1 LAST PART_NUMBER G21796-026
J 0
(-185 2125);
DISPLAY 0.617021 (-185 2125);
PAINT BLUE (-185 2125);
FORCEPROP 1 LAST LOCATION R8D21
J 0
(-180 2375);
DISPLAY 0.617021 (-180 2375);
PAINT AQUA (-180 2375);
FORCEPROP 2 LAST CDS_LIB mstr_discrete
R 3
J 0
(-225 2250);
PAINT MONO (-225 2250);
DISPLAY INVISIBLE (-225 2250);
FORCEPROP 2 LAST CDS_LOCATION R8D21
J 0
(-180 2375);
DISPLAY 0.617021 (-180 2375);
PAINT AQUA (-180 2375);
DISPLAY INVISIBLE (-180 2375);
FORCEPROP 2 LAST SEC_TYPE 0402
J 0
(-175 2475);
DISPLAY 1.021277 (-175 2475);
PAINT ORANGE (-175 2475);
DISPLAY INVISIBLE (-175 2475);
FORCEPROP 2 LAST SEC 1
J 0
(-175 2475);
DISPLAY 0.680851 (-175 2475);
PAINT MONO (-175 2475);
DISPLAY INVISIBLE (-175 2475);
FORCEPROP 1 LAST PATH I120
J 0
(-175 2425);
DISPLAY 0.978723 (-175 2425);
PAINT WHITE (-175 2425);
DISPLAY INVISIBLE (-175 2425);
FORCEPROP 2 LAST BOM_COST SB
R 3
J 0
(0 2200);
PAINT ORANGE (0 2200);
DISPLAY INVISIBLE (0 2200);
FORCEPROP 2 LAST ROOM SB
J 0
(-275 2075);
DISPLAY 1.361702 (-275 2075);
PAINT ORANGE (-275 2075);
DISPLAY INVISIBLE (-275 2075);
FORCEADD RES..2
(-1525 2250);
FORCEPROP 1 LASTPIN (-1525 2150) $PN 2
J 0
(-1520 2160);
DISPLAY 0.617021 (-1520 2160);
PAINT ORANGE (-1520 2160);
FORCEPROP 1 LASTPIN (-1525 2350) $PN 1
J 0
(-1520 2312);
DISPLAY 0.617021 (-1520 2312);
PAINT ORANGE (-1520 2312);
FORCEPROP 1 LAST WATTAGE 1/16W
J 0
(-1485 2225);
DISPLAY 0.617021 (-1485 2225);
PAINT SKYBLUE (-1485 2225);
FORCEPROP 1 LAST MATERIAL CHIP
J 0
(-1485 2175);
DISPLAY 0.617021 (-1485 2175);
PAINT SKYBLUE (-1485 2175);
FORCEPROP 1 LAST PACK_TYPE 0402
J 0
(-1485 2075);
DISPLAY 0.617021 (-1485 2075);
PAINT SKYBLUE (-1485 2075);
FORCEPROP 1 LAST TOLERANCE 1%
J 0
(-1480 2275);
DISPLAY 0.617021 (-1480 2275);
PAINT SKYBLUE (-1480 2275);
FORCEPROP 1 LAST VALUE 4.75K
J 0
(-1480 2325);
DISPLAY 0.617021 (-1480 2325);
PAINT SKYBLUE (-1480 2325);
FORCEPROP 1 LAST PART_NUMBER G21796-072
J 0
(-1485 2125);
DISPLAY 0.617021 (-1485 2125);
PAINT BLUE (-1485 2125);
FORCEPROP 1 LAST LOCATION R7D30
J 0
(-1480 2375);
DISPLAY 0.617021 (-1480 2375);
PAINT AQUA (-1480 2375);
FORCEPROP 2 LAST CDS_LIB mstr_discrete
J 0
(-1525 2250);
PAINT ORANGE (-1525 2250);
DISPLAY INVISIBLE (-1525 2250);
FORCEPROP 2 LAST CDS_LOCATION R7D30
J 0
(-1480 2375);
DISPLAY 0.617021 (-1480 2375);
PAINT AQUA (-1480 2375);
DISPLAY INVISIBLE (-1480 2375);
FORCEPROP 1 LAST PATH I121
J 0
(-1475 2425);
DISPLAY 0.978723 (-1475 2425);
PAINT WHITE (-1475 2425);
DISPLAY INVISIBLE (-1475 2425);
FORCEPROP 2 LAST SEC 1
J 0
(-1475 2475);
PAINT MONO (-1475 2475);
DISPLAY INVISIBLE (-1475 2475);
FORCEPROP 2 LAST BOM_COST DEBUG
J 0
(-1475 2475);
DISPLAY 1.021277 (-1475 2475);
PAINT ORANGE (-1475 2475);
DISPLAY INVISIBLE (-1475 2475);
FORCEPROP 2 LAST SEC_TYPE 0402
J 0
(-1475 2475);
DISPLAY 1.021277 (-1475 2475);
PAINT ORANGE (-1475 2475);
DISPLAY INVISIBLE (-1475 2475);
FORCEPROP 2 LAST ROOM UART_MUX
J 0
(-1475 2425);
DISPLAY 1.021277 (-1475 2425);
PAINT ORANGE (-1475 2425);
DISPLAY INVISIBLE (-1475 2425);
FORCEADD P3V3_STBY..1
(-1525 2500);
FORCEPROP 3 LASTPIN (-1525 2450) SIG_NAME P3V3_STBY\g
J 0
(-1515 2460);
DISPLAY 0.659574 (-1515 2460);
PAINT MONO (-1515 2460);
DISPLAY INVISIBLE (-1515 2460);
FORCEPROP 1 LAST BODY_TYPE PLUMBING
J 0
(-1570 2457);
DISPLAY 0.340426 (-1570 2457);
PAINT GREEN (-1570 2457);
DISPLAY INVISIBLE (-1570 2457);
FORCEPROP 2 LAST CDS_LIB mstr_symbols
J 0
(-1525 2500);
PAINT ORANGE (-1525 2500);
DISPLAY INVISIBLE (-1525 2500);
FORCEPROP 1 LAST SIZE 1B
J 0
(-1480 2522);
DISPLAY 0.340426 (-1480 2522);
PAINT GREEN (-1480 2522);
DISPLAY INVISIBLE (-1480 2522);
FORCEPROP 1 LAST PATH I122
J 0
(-1480 2502);
DISPLAY 0.340426 (-1480 2502);
PAINT GREEN (-1480 2502);
DISPLAY INVISIBLE (-1480 2502);
FORCEPROP 1 LAST HDL_POWER P3V3_STBY
J 0
(-1825 2375);
DISPLAY 0.872340 (-1825 2375);
PAINT ORANGE (-1825 2375);
DISPLAY INVISIBLE (-1825 2375);
FORCEPROP 1 LAST VOLTAGE 3.3V
J 0
(-1570 2457);
DISPLAY 0.340426 (-1570 2457);
PAINT SKYBLUE (-1570 2457);
DISPLAY INVISIBLE (-1570 2457);
FORCEADD GND..1
(-300 1600);
FORCEPROP 3 LASTPIN (-300 1650) SIG_NAME GND\g
J 0
(-290 1660);
DISPLAY 0.659574 (-290 1660);
PAINT MONO (-290 1660);
DISPLAY INVISIBLE (-290 1660);
FORCEPROP 2 LAST CDS_LIB mstr_symbols
J 0
(-300 1600);
PAINT MONO (-300 1600);
DISPLAY INVISIBLE (-300 1600);
FORCEPROP 1 LAST BODY_TYPE PLUMBING
J 0
(-345 1557);
DISPLAY 0.340426 (-345 1557);
PAINT GREEN (-345 1557);
DISPLAY INVISIBLE (-345 1557);
FORCEPROP 1 LAST PATH I123
J 0
(-225 1600);
DISPLAY 0.872340 (-225 1600);
PAINT AQUA (-225 1600);
DISPLAY INVISIBLE (-225 1600);
FORCEPROP 1 LAST SIZE 1B
J 0
(-225 1550);
DISPLAY 0.872340 (-225 1550);
PAINT AQUA (-225 1550);
DISPLAY INVISIBLE (-225 1550);
FORCEPROP 1 LAST HDL_POWER GND
J 0
(-300 1750);
DISPLAY 0.872340 (-300 1750);
PAINT GREEN (-300 1750);
DISPLAY INVISIBLE (-300 1750);
FORCEPROP 1 LAST VOLTAGE 0.0V
J 0
(-345 1557);
DISPLAY 0.340426 (-345 1557);
PAINT SKYBLUE (-345 1557);
DISPLAY INVISIBLE (-345 1557);
FORCEADD CONN12_C73564003..1
(-775 1900);
FORCEPROP 2 LASTPIN (-1125 1800) $PN 9
J 2
(-1135 1810);
DISPLAY 0.617021 (-1135 1810);
PAINT ORANGE (-1135 1810);
FORCEPROP 2 LASTPIN (-1125 1750) $PN 11
J 2
(-1135 1760);
DISPLAY 0.617021 (-1135 1760);
PAINT ORANGE (-1135 1760);
FORCEPROP 2 LASTPIN (-1125 1850) $PN 7
J 2
(-1135 1860);
DISPLAY 0.617021 (-1135 1860);
PAINT ORANGE (-1135 1860);
FORCEPROP 2 LASTPIN (-1125 1950) $PN 3
J 2
(-1135 1960);
DISPLAY 0.617021 (-1135 1960);
PAINT ORANGE (-1135 1960);
FORCEPROP 2 LASTPIN (-1125 2000) $PN 1
J 2
(-1135 2010);
DISPLAY 0.617021 (-1135 2010);
PAINT ORANGE (-1135 2010);
FORCEPROP 2 LASTPIN (-1125 1900) $PN 5
J 2
(-1135 1910);
DISPLAY 0.617021 (-1135 1910);
PAINT ORANGE (-1135 1910);
FORCEPROP 2 LASTPIN (-425 1850) $PN 8
J 0
(-415 1860);
DISPLAY 0.617021 (-415 1860);
PAINT ORANGE (-415 1860);
FORCEPROP 2 LASTPIN (-425 1800) $PN 10
J 0
(-415 1810);
DISPLAY 0.617021 (-415 1810);
PAINT ORANGE (-415 1810);
FORCEPROP 2 LASTPIN (-425 1750) $PN 12
J 0
(-415 1760);
DISPLAY 0.617021 (-415 1760);
PAINT ORANGE (-415 1760);
FORCEPROP 2 LASTPIN (-425 1900) $PN 6
J 0
(-415 1910);
DISPLAY 0.617021 (-415 1910);
PAINT ORANGE (-415 1910);
FORCEPROP 2 LASTPIN (-425 1950) $PN 4
J 0
(-415 1960);
DISPLAY 0.617021 (-415 1960);
PAINT ORANGE (-415 1960);
FORCEPROP 2 LASTPIN (-425 2000) $PN 2
J 0
(-415 2010);
DISPLAY 0.617021 (-415 2010);
PAINT ORANGE (-415 2010);
FORCEPROP 1 LAST MATERIAL CONN
J 0
(-1075 2200);
DISPLAY 0.617021 (-1075 2200);
PAINT SKYBLUE (-1075 2200);
FORCEPROP 1 LAST PART_NUMBER C73564-003
J 0
(-1075 1600);
DISPLAY 0.617021 (-1075 1600);
PAINT BLUE (-1075 1600);
FORCEPROP 1 LAST LOCATION J8G2
J 0
(-1075 2250);
DISPLAY 0.617021 (-1075 2250);
PAINT AQUA (-1075 2250);
FORCEPROP 0 LAST BOM_COST SB
J 0
(-1075 2450);
DISPLAY 1.021277 (-1075 2450);
PAINT ORANGE (-1075 2450);
DISPLAY INVISIBLE (-1075 2450);
FORCEPROP 1 LAST PATH I124
J 0
(-775 2200);
PAINT GREEN (-775 2200);
DISPLAY INVISIBLE (-775 2200);
FORCEPROP 2 LAST CDS_LIB mstr_conn
J 0
(-775 1900);
PAINT ORANGE (-775 1900);
DISPLAY INVISIBLE (-775 1900);
FORCEPROP 2 LAST SEC 1
J 0
(-1075 2300);
DISPLAY 0.680851 (-1075 2300);
PAINT MONO (-1075 2300);
DISPLAY INVISIBLE (-1075 2300);
FORCEPROP 2 LAST SEC_TYPE PIP
J 0
(-1075 2300);
DISPLAY 1.021277 (-1075 2300);
PAINT ORANGE (-1075 2300);
DISPLAY INVISIBLE (-1075 2300);
FORCEPROP 0 LAST ROOM SB
J 0
(-1075 2350);
DISPLAY 1.021277 (-1075 2350);
PAINT ORANGE (-1075 2350);
DISPLAY INVISIBLE (-1075 2350);
FORCEPROP 1 LAST PACK_TYPE PIP
J 0
(-1075 2300);
PAINT SKYBLUE (-1075 2300);
DISPLAY INVISIBLE (-1075 2300);
FORCEADD GND..1
(-1250 1575);
FORCEPROP 3 LASTPIN (-1250 1625) SIG_NAME GND\g
J 0
(-1240 1635);
DISPLAY 0.659574 (-1240 1635);
PAINT MONO (-1240 1635);
DISPLAY INVISIBLE (-1240 1635);
FORCEPROP 1 LAST BODY_TYPE PLUMBING
J 0
(-1295 1532);
DISPLAY 0.340426 (-1295 1532);
PAINT GREEN (-1295 1532);
DISPLAY INVISIBLE (-1295 1532);
FORCEPROP 1 LAST SIZE 1B
J 0
(-1175 1525);
DISPLAY 0.872340 (-1175 1525);
PAINT AQUA (-1175 1525);
DISPLAY INVISIBLE (-1175 1525);
FORCEPROP 1 LAST PATH I125
J 0
(-1175 1575);
DISPLAY 0.872340 (-1175 1575);
PAINT AQUA (-1175 1575);
DISPLAY INVISIBLE (-1175 1575);
FORCEPROP 2 LAST CDS_LIB mstr_symbols
J 0
(-1250 1575);
PAINT ORANGE (-1250 1575);
DISPLAY INVISIBLE (-1250 1575);
FORCEPROP 1 LAST HDL_POWER GND
J 0
(-1250 1725);
DISPLAY 0.872340 (-1250 1725);
PAINT GREEN (-1250 1725);
DISPLAY INVISIBLE (-1250 1725);
FORCEPROP 1 LAST VOLTAGE 0.0V
J 0
(-1295 1532);
DISPLAY 0.340426 (-1295 1532);
PAINT SKYBLUE (-1295 1532);
DISPLAY INVISIBLE (-1295 1532);
FORCEADD OFFPAGE..5
(-2225 1950);
FORCEPROP 2 LAST $XR0 118 
J 0
(-2480 1950);
DISPLAY 0.638298 (-2480 1950);
PAINT MONO (-2480 1950);
FORCEPROP 2 LAST $XR1 249 
J 0
(-2600 1950);
DISPLAY 0.638298 (-2600 1950);
PAINT MONO (-2600 1950);
FORCEPROP 2 LAST $XR2 145 
J 0
(-2720 1950);
DISPLAY 0.638298 (-2720 1950);
PAINT MONO (-2720 1950);
FORCEPROP 2 LAST $XR3 ?
J 0
(-2720 1950);
DISPLAY 0.638298 (-2720 1950);
PAINT MONO (-2720 1950);
FORCEPROP 1 LAST OFFPAGE TRUE
J 0
(-1900 1825);
DISPLAY 0.872340 (-1900 1825);
PAINT GREEN (-1900 1825);
DISPLAY INVISIBLE (-1900 1825);
FORCEPROP 1 LAST COMMENT_BODY TRUE
J 0
(-2125 1875);
DISPLAY 0.872340 (-2125 1875);
PAINT GREEN (-2125 1875);
DISPLAY INVISIBLE (-2125 1875);
FORCEPROP 2 LAST CDS_LIB mstr_standard
J 0
(-2225 1950);
PAINT ORANGE (-2225 1950);
DISPLAY INVISIBLE (-2225 1950);
FORCEPROP 2 LAST PATH I126
J 0
(-2500 2000);
DISPLAY 1.021277 (-2500 2000);
PAINT ORANGE (-2500 2000);
DISPLAY INVISIBLE (-2500 2000);
FORCEADD OFFPAGE..5
(-2225 1800);
FORCEPROP 2 LAST $XR0 190 
J 0
(-2480 1800);
DISPLAY 0.638298 (-2480 1800);
PAINT MONO (-2480 1800);
FORCEPROP 1 LAST OFFPAGE TRUE
J 0
(-1900 1675);
DISPLAY 0.872340 (-1900 1675);
PAINT GREEN (-1900 1675);
DISPLAY INVISIBLE (-1900 1675);
FORCEPROP 2 LAST CDS_LIB mstr_standard
J 0
(-2225 1800);
PAINT ORANGE (-2225 1800);
DISPLAY INVISIBLE (-2225 1800);
FORCEPROP 1 LAST COMMENT_BODY TRUE
J 0
(-2125 1725);
DISPLAY 0.872340 (-2125 1725);
PAINT GREEN (-2125 1725);
DISPLAY INVISIBLE (-2125 1725);
FORCEPROP 2 LAST PATH I127
J 0
(-2500 1850);
DISPLAY 1.021277 (-2500 1850);
PAINT ORANGE (-2500 1850);
DISPLAY INVISIBLE (-2500 1850);
FORCEADD P3V3_STBY..1
(-4275 5150);
FORCEPROP 3 LASTPIN (-4275 5100) SIG_NAME P3V3_STBY\g
J 0
(-4265 5110);
DISPLAY 0.659574 (-4265 5110);
PAINT MONO (-4265 5110);
DISPLAY INVISIBLE (-4265 5110);
FORCEPROP 1 LAST BODY_TYPE PLUMBING
J 0
(-4320 5107);
DISPLAY 0.340426 (-4320 5107);
PAINT GREEN (-4320 5107);
DISPLAY INVISIBLE (-4320 5107);
FORCEPROP 1 LAST PATH I128
J 0
(-4230 5152);
DISPLAY 0.340426 (-4230 5152);
PAINT GREEN (-4230 5152);
DISPLAY INVISIBLE (-4230 5152);
FORCEPROP 2 LAST CDS_LIB mstr_symbols
J 0
(-4275 5150);
PAINT ORANGE (-4275 5150);
DISPLAY INVISIBLE (-4275 5150);
FORCEPROP 1 LAST SIZE 1B
J 0
(-4230 5172);
DISPLAY 0.340426 (-4230 5172);
PAINT GREEN (-4230 5172);
DISPLAY INVISIBLE (-4230 5172);
FORCEPROP 1 LAST HDL_POWER P3V3_STBY
J 0
(-4575 5025);
DISPLAY 0.872340 (-4575 5025);
PAINT ORANGE (-4575 5025);
DISPLAY INVISIBLE (-4575 5025);
FORCEPROP 1 LAST VOLTAGE 3.3V
J 0
(-4320 5107);
DISPLAY 0.340426 (-4320 5107);
PAINT SKYBLUE (-4320 5107);
DISPLAY INVISIBLE (-4320 5107);
FORCEADD RES..1
R 1
(-4275 4900);
FORCEPROP 1 LASTPIN (-4275 4800) $PN 1
J 0
(-4312 4812);
DISPLAY 0.617021 (-4312 4812);
PAINT MONO (-4312 4812);
FORCEPROP 1 LASTPIN (-4275 5000) $PN 2
J 0
(-4312 4962);
DISPLAY 0.617021 (-4312 4962);
PAINT MONO (-4312 4962);
FORCEPROP 1 LAST WATTAGE 1/16W
J 0
(-4250 4825);
DISPLAY 0.617021 (-4250 4825);
PAINT SKYBLUE (-4250 4825);
FORCEPROP 1 LAST MATERIAL CHIP
J 0
(-4250 4775);
DISPLAY 0.617021 (-4250 4775);
PAINT SKYBLUE (-4250 4775);
FORCEPROP 1 LAST PACK_TYPE 0402
J 0
(-4250 4650);
DISPLAY 0.617021 (-4250 4650);
PAINT SKYBLUE (-4250 4650);
FORCEPROP 1 LAST TOLERANCE 1%
J 0
(-4250 4875);
DISPLAY 0.617021 (-4250 4875);
PAINT SKYBLUE (-4250 4875);
FORCEPROP 1 LAST VALUE 2.21K
J 0
(-4250 4925);
DISPLAY 0.617021 (-4250 4925);
PAINT SKYBLUE (-4250 4925);
FORCEPROP 1 LAST PART_NUMBER G21796-112
J 0
(-4250 4725);
DISPLAY 0.617021 (-4250 4725);
PAINT BLUE (-4250 4725);
FORCEPROP 1 LAST LOCATION R9A16
J 0
(-4250 5000);
DISPLAY 0.617021 (-4250 5000);
PAINT AQUA (-4250 5000);
FORCEPROP 1 LAST PATH I129
R 1
J 0
(-4425 4850);
DISPLAY 0.978723 (-4425 4850);
PAINT WHITE (-4425 4850);
DISPLAY INVISIBLE (-4425 4850);
FORCEPROP 2 LAST CDS_LIB mstr_discrete
J 0
(-4275 4900);
PAINT MONO (-4275 4900);
DISPLAY INVISIBLE (-4275 4900);
FORCEPROP 2 LAST BOM_COST SB
J 0
(-4250 5050);
PAINT MONO (-4250 5050);
DISPLAY INVISIBLE (-4250 5050);
FORCEPROP 2 LAST CDS_LOCATION R9A16
J 0
(-4250 5000);
DISPLAY 0.617021 (-4250 5000);
PAINT AQUA (-4250 5000);
DISPLAY INVISIBLE (-4250 5000);
FORCEPROP 2 LAST $SEC 1
J 0
(-4250 5050);
DISPLAY 0.936170 (-4250 5050);
PAINT MONO (-4250 5050);
DISPLAY INVISIBLE (-4250 5050);
FORCEPROP 2 LAST CDS_SEC 1
J 0
(-4250 5050);
DISPLAY 1.404255 (-4250 5050);
PAINT ORANGE (-4250 5050);
DISPLAY INVISIBLE (-4250 5050);
FORCEPROP 2 LAST ROOM SB
J 0
(-4250 5050);
PAINT MONO (-4250 5050);
DISPLAY INVISIBLE (-4250 5050);
FORCEADD GND..1
(-4850 4325);
FORCEPROP 3 LASTPIN (-4850 4375) SIG_NAME GND\g
J 0
(-4840 4385);
DISPLAY 0.659574 (-4840 4385);
PAINT MONO (-4840 4385);
DISPLAY INVISIBLE (-4840 4385);
FORCEPROP 1 LAST BODY_TYPE PLUMBING
J 0
(-4895 4282);
DISPLAY 0.340426 (-4895 4282);
PAINT GREEN (-4895 4282);
DISPLAY INVISIBLE (-4895 4282);
FORCEPROP 2 LAST BOM_COST SB
J 0
(-4900 4400);
PAINT MONO (-4900 4400);
DISPLAY INVISIBLE (-4900 4400);
FORCEPROP 1 LAST SIZE 1B
J 0
(-4775 4275);
DISPLAY 1.404255 (-4775 4275);
PAINT GREEN (-4775 4275);
DISPLAY INVISIBLE (-4775 4275);
FORCEPROP 2 LAST CDS_LIB mstr_symbols
J 0
(-4850 4325);
PAINT MONO (-4850 4325);
DISPLAY INVISIBLE (-4850 4325);
FORCEPROP 1 LAST PATH I130
J 0
(-4775 4325);
DISPLAY 0.872340 (-4775 4325);
PAINT AQUA (-4775 4325);
DISPLAY INVISIBLE (-4775 4325);
FORCEPROP 2 LAST ROOM WBG_HEADERS_BIOS
J 0
(-5400 4400);
PAINT MONO (-5400 4400);
DISPLAY INVISIBLE (-5400 4400);
FORCEPROP 1 LAST HDL_POWER GND
J 0
(-4850 4475);
DISPLAY 1.404255 (-4850 4475);
PAINT GREEN (-4850 4475);
DISPLAY INVISIBLE (-4850 4475);
FORCEPROP 1 LAST VOLTAGE 0
J 0
(-4850 4325);
PAINT SKYBLUE (-4850 4325);
DISPLAY INVISIBLE (-4850 4325);
FORCEADD CONN4_D42317002..1
R 2
(-5075 4600);
FORCEPROP 2 LASTPIN (-4925 4550) $PN 3
J 0
(-4915 4560);
DISPLAY 0.617021 (-4915 4560);
PAINT MONO (-4915 4560);
FORCEPROP 2 LASTPIN (-4925 4500) $PN 4
J 0
(-4915 4510);
DISPLAY 0.617021 (-4915 4510);
PAINT MONO (-4915 4510);
FORCEPROP 2 LASTPIN (-4925 4600) $PN 2
J 0
(-4915 4610);
DISPLAY 0.617021 (-4915 4610);
PAINT MONO (-4915 4610);
FORCEPROP 2 LASTPIN (-4925 4650) $PN 1
J 0
(-4915 4660);
DISPLAY 0.617021 (-4915 4660);
PAINT MONO (-4915 4660);
FORCEPROP 1 LAST MATERIAL CONN
J 2
(-4975 4800);
DISPLAY 0.617021 (-4975 4800);
PAINT SKYBLUE (-4975 4800);
FORCEPROP 1 LAST PART_NUMBER D42317-002
J 2
(-4975 4400);
DISPLAY 0.617021 (-4975 4400);
PAINT BLUE (-4975 4400);
FORCEPROP 1 LAST LOCATION J9A1
J 2
(-4975 4850);
DISPLAY 0.617021 (-4975 4850);
PAINT AQUA (-4975 4850);
FORCEPROP 1 LAST PATH I131
J 2
(-5125 4800);
PAINT GREEN (-5125 4800);
DISPLAY INVISIBLE (-5125 4800);
FORCEPROP 2 LAST CDS_LIB mstr_conn
J 0
(-5075 4600);
PAINT ORANGE (-5075 4600);
DISPLAY INVISIBLE (-5075 4600);
FORCEPROP 0 LAST BOM_COST SB
J 0
(-4975 4950);
PAINT MONO (-4975 4950);
DISPLAY INVISIBLE (-4975 4950);
FORCEPROP 2 LAST CDS_SEC 1
J 0
(-4975 4900);
PAINT MONO (-4975 4900);
DISPLAY INVISIBLE (-4975 4900);
FORCEPROP 2 LAST $SEC 1
J 0
(-4975 4900);
PAINT MONO (-4975 4900);
DISPLAY INVISIBLE (-4975 4900);
FORCEPROP 2 LAST CDS_LOCATION J9A1
J 2
(-4975 4850);
DISPLAY 0.617021 (-4975 4850);
PAINT AQUA (-4975 4850);
DISPLAY INVISIBLE (-4975 4850);
FORCEPROP 2 LAST ROOM SB
J 0
(-4975 5000);
PAINT MONO (-4975 5000);
DISPLAY INVISIBLE (-4975 5000);
FORCEPROP 1 LAST PACK_TYPE PIP
J 2
(-4975 4900);
PAINT SKYBLUE (-4975 4900);
DISPLAY INVISIBLE (-4975 4900);
FORCEADD DESIGN_NOTE..1
(-4800 2500);
FORCEPROP 0 LAST L4 SET TO HIGH IMPEDANCE
J 0
(-5000 2200);
DISPLAY 0.808511 (-5000 2200);
PAINT ORANGE (-5000 2200);
FORCEPROP 0 LAST L2 WHEN JUMPER IS INSTALLED ON PINS 3 AND 5, SRST# ON BMC
J 0
(-5000 2300);
DISPLAY 0.808511 (-5000 2300);
PAINT ORANGE (-5000 2300);
FORCEPROP 0 LAST L1 BMC DISABLED WHEN JUMPER IS INSTALLED ON PINS 3 AND 5
J 0
(-5000 2400);
DISPLAY 0.808511 (-5000 2400);
PAINT ORANGE (-5000 2400);
FORCEPROP 0 LAST L3 IS PULLED LOW AND ALL PINS ON BMC ARE
J 0
(-5000 2250);
DISPLAY 0.808511 (-5000 2250);
PAINT ORANGE (-5000 2250);
FORCEPROP 1 LAST COMMENT_BODY TRUE
J 0
(-4775 2600);
DISPLAY 0.978723 (-4775 2600);
PAINT ORANGE (-4775 2600);
DISPLAY INVISIBLE (-4775 2600);
FORCEPROP 2 LAST CDS_LIB mstr_symbols
J 0
(-4800 2500);
PAINT MONO (-4800 2500);
DISPLAY INVISIBLE (-4800 2500);
FORCEADD DESIGN_NOTE..1
(-4800 1650);
FORCEPROP 0 LAST L4 WILL STAY SELECTED AFTER A POWER CYCLE
J 0
(-5000 1350);
DISPLAY 0.808511 (-5000 1350);
PAINT ORANGE (-5000 1350);
FORCEPROP 0 LAST L3 UART CHANNEL SELECTED ON THE OUTPUT OF UART MUX
J 0
(-5000 1400);
DISPLAY 0.808511 (-5000 1400);
PAINT ORANGE (-5000 1400);
FORCEPROP 0 LAST L2 WHEN JUMPER IS INSTALLED ON PINS 7 AND 11, THE CURRENT
J 0
(-5000 1450);
DISPLAY 0.808511 (-5000 1450);
PAINT ORANGE (-5000 1450);
FORCEPROP 0 LAST L1 UART CHANNEL LOCKED WHEN JUMPER IS INSTALLED ON PINS 7 AND 11
J 0
(-5000 1550);
DISPLAY 0.808511 (-5000 1550);
PAINT ORANGE (-5000 1550);
FORCEPROP 1 LAST COMMENT_BODY TRUE
J 0
(-4775 1750);
DISPLAY 0.978723 (-4775 1750);
PAINT ORANGE (-4775 1750);
DISPLAY INVISIBLE (-4775 1750);
FORCEPROP 2 LAST CDS_LIB mstr_symbols
J 0
(-4800 1650);
PAINT ORANGE (-4800 1650);
DISPLAY INVISIBLE (-4800 1650);
FORCEADD DESIGN_NOTE..1
(-725 5250);
FORCEPROP 0 LAST L1 QAT ENABLE
J 0
(-925 5125);
DISPLAY 1.021277 (-925 5125);
PAINT ORANGE (-925 5125);
FORCEPROP 1 LAST COMMENT_BODY TRUE
J 0
(-700 5350);
DISPLAY 1.361702 (-700 5350);
PAINT WHITE (-700 5350);
DISPLAY INVISIBLE (-700 5350);
FORCEPROP 2 LAST CDS_LIB mstr_symbols
J 0
(-725 5250);
PAINT ORANGE (-725 5250);
DISPLAY INVISIBLE (-725 5250);
FORCEADD DESIGN_NOTE..1
(700 2475);
FORCEPROP 0 LAST L1 IE DISABLED WHEN JUMPER IS INSTALLED ON PINS 4 AND 6
J 0
(500 2375);
DISPLAY 0.808511 (500 2375);
PAINT ORANGE (500 2375);
FORCEPROP 2 LAST CDS_LIB mstr_symbols
J 0
(700 2475);
PAINT ORANGE (700 2475);
DISPLAY INVISIBLE (700 2475);
FORCEPROP 1 LAST COMMENT_BODY TRUE
J 0
(725 2575);
DISPLAY 0.978723 (725 2575);
PAINT ORANGE (725 2575);
DISPLAY INVISIBLE (725 2575);
FORCEADD DESIGN_NOTE..1
(200 1450);
FORCEPROP 0 LAST L1 ADR DELAY IS DISABLED WHEN JUMPER IS INSTALLED ON PINS 10 AND 12
J 0
(0 1350);
DISPLAY 0.808511 (0 1350);
PAINT ORANGE (0 1350);
FORCEPROP 2 LAST CDS_LIB mstr_symbols
J 0
(200 1450);
PAINT ORANGE (200 1450);
DISPLAY INVISIBLE (200 1450);
FORCEPROP 1 LAST COMMENT_BODY TRUE
J 0
(225 1550);
DISPLAY 0.978723 (225 1550);
PAINT ORANGE (225 1550);
DISPLAY INVISIBLE (225 1550);
FORCEADD CAD_NOTE..1
(-1100 1375);
FORCEPROP 0 LAST L1 PLACE TO THE LEFT OF J7G2
J 0
(-1250 1225);
DISPLAY 1.021277 (-1250 1225);
PAINT ORANGE (-1250 1225);
FORCEPROP 1 LAST COMMENT_BODY TRUE
J 0
(-1075 1475);
DISPLAY 0.978723 (-1075 1475);
PAINT ORANGE (-1075 1475);
DISPLAY INVISIBLE (-1075 1475);
FORCEPROP 2 LAST CDS_LIB mstr_symbols
J 0
(-1100 1375);
PAINT ORANGE (-1100 1375);
DISPLAY INVISIBLE (-1100 1375);
FORCEADD DESIGN_NOTE..1
(-4325 4125);
FORCEPROP 0 LAST L1 SATA RAID KEY
J 0
(-4525 4000);
DISPLAY 1.021277 (-4525 4000);
PAINT ORANGE (-4525 4000);
FORCEPROP 1 LAST COMMENT_BODY TRUE
J 0
(-4300 4225);
DISPLAY 1.361702 (-4300 4225);
PAINT WHITE (-4300 4225);
DISPLAY INVISIBLE (-4300 4225);
FORCEPROP 2 LAST CDS_LIB mstr_symbols
J 0
(-4325 4125);
PAINT MONO (-4325 4125);
DISPLAY INVISIBLE (-4325 4125);
FORCEADD DNS..2
(-2145 4320);
PAINT RED (-2145 4320);
FORCEPROP 1 LAST COMMENT_BODY TRUE
R 1
J 0
(-2070 4095);
DISPLAY 0.872340 (-2070 4095);
PAINT GREEN (-2070 4095);
DISPLAY INVISIBLE (-2070 4095);
FORCEPROP 2 LAST CDS_LIB mstr_misc
J 0
(-2145 4320);
PAINT ORANGE (-2145 4320);
DISPLAY INVISIBLE (-2145 4320);
FORCEADD INTEL_CORP_BPAGE..1
(2650 500);
FORCEPROP 1 LAST CDS_CON_LAST_MODIFIED Tue Dec 01 11:52:01 2015
J 0
(1225 825);
PAINT ORANGE (1225 825);
DISPLAY INVISIBLE (1225 825);
FORCEPROP 1 LAST CUSTOM_TXT_CDS <CURRENT_DESIGN_SHEET> OF <TOTAL_DESIGN_SHEETS>
J 0
(2150 525);
PAINT GREEN (2150 525);
FORCEPROP 1 LAST CUSTOM_TXT_CDS <CON_LAST_MODIFIED>
J 0
(725 850);
PAINT GREEN (725 850);
FORCEPROP 2 LAST CUSTOM_TXT_CDS <XR_PAGE_TITLE>
J 0
(-5240 5750);
DISPLAY 0.638298 (-5240 5750);
PAINT PINK (-5240 5750);
DISPLAY INVISIBLE (-5240 5750);
FORCEPROP 1 LAST SCH_TITLE LBG HEADERS (1/3)
J 0
(-5300 550);
DISPLAY 1.212766 (-5300 550);
PAINT ORANGE (-5300 550);
FORCEPROP 1 LAST SCH_ADDRESS1 2200 Mission College Blvd.
J 0
(-1325 625);
DISPLAY 0.617021 (-1325 625);
PAINT GREEN (-1325 625);
FORCEPROP 1 LAST SCH_ADDRESS2 P.O. BOX 58119
J 0
(-1325 575);
DISPLAY 0.617021 (-1325 575);
PAINT GREEN (-1325 575);
FORCEPROP 1 LAST SCH_ADDRESS3 Santa Clara, CA 95052-8119
J 0
(-1325 525);
DISPLAY 0.617021 (-1325 525);
PAINT GREEN (-1325 525);
FORCEPROP 1 LAST SCH_REV 2.420
J 0
(2400 650);
DISPLAY 0.978723 (2400 650);
PAINT YELLOW (2400 650);
FORCEPROP 1 LAST SCH_DEPT BESD
J 1
(-1800 600);
DISPLAY 1.212766 (-1800 600);
PAINT YELLOW (-1800 600);
FORCEPROP 1 LAST SCH_NUMBER H4694802
J 0
(1350 650);
DISPLAY 1.212766 (1350 650);
PAINT YELLOW (1350 650);
FORCEPROP 2 LAST PAGE_BORDER TRUE
J 0
(-5240 5750);
DISPLAY 0.851064 (-5240 5750);
PAINT PINK (-5240 5750);
DISPLAY INVISIBLE (-5240 5750);
FORCEPROP 1 LAST COMMENT_BODY TRUE
J 0
(2662 512);
DISPLAY 0.468085 (2662 512);
PAINT GREEN (2662 512);
DISPLAY INVISIBLE (2662 512);
FORCEPROP 2 LAST CDS_LIB mstr_symbols
J 0
(2650 500);
PAINT MONO (2650 500);
DISPLAY INVISIBLE (2650 500);
FORCEPROP 2 LAST CDS_XR_PAGE_TITLE CR-135 : @BASEBOARD_FAB2_LIB.BASEBOARD_FAB2(SCH_1):PAGE135
J 0
(-5240 5750);
DISPLAY 0.638298 (-5240 5750);
PAINT PINK (-5240 5750);
DISPLAY INVISIBLE (-5240 5750);
WIRE 16 -1 (200 2475)(200 2325);
WIRE 16 -1 (-2150 4975)(-2150 4875);
WIRE 16 -1 (-2150 4225)(-2150 4175);
WIRE 16 -1 (-3875 5100)(-3875 5000);
WIRE 16 -1 (-225 2475)(-225 2350);
WIRE 16 -1 (-1525 2350)(-1525 2450);
WIRE 16 -1 (-300 1900)(-425 1900);
WIRE 16 -1 (-300 1750)(-300 1900);
WIRE 16 -1 (-300 1650)(-300 1750);
WIRE 16 -1 (-300 1750)(-425 1750);
WIRE 16 -1 (-1125 1900)(-1250 1900);
WIRE 16 -1 (-1250 1750)(-1250 1900);
WIRE 16 -1 (-1125 1750)(-1250 1750);
WIRE 16 -1 (-1250 1625)(-1250 1750);
WIRE 16 -1 (-4275 5100)(-4275 5000);
WIRE 16 -1 (-4925 4650)(-4850 4650);
WIRE 16 -1 (-4850 4650)(-4850 4550);
WIRE 16 -1 (-4925 4550)(-4850 4550);
WIRE 16 -1 (-4850 4550)(-4850 4375);
WIRE 16 -1 (-4925 4600)(-4275 4600);
FORCEPROP 2 LAST SIG_NAME PU_KEY_CONN_PIN2_R
J 0
(-4760 4610);
DISPLAY 0.617021 (-4760 4610);
PAINT ORANGE (-4760 4610);
FORCEPROP 2 LASTPROP $XRERR UNIQUE?
J 0
(-5000 4610);
DISPLAY 0.638298 (-5000 4610);
PAINT MONO (-5000 4610);
DISPLAY INVISIBLE (-5000 4610);
WIRE 16 -1 (-4275 4800)(-4275 4600);
WIRE 16 -1 (-2625 3425)(-2625 2825);
WIRE 16 -1 (-2175 2000)(-1125 2000);
FORCEPROP 2 LAST SIG_NAME TP_JUMPER_BLOCK_1_1
J 0
(-2110 2010);
DISPLAY 0.617021 (-2110 2010);
PAINT ORANGE (-2110 2010);
FORCEPROP 2 LASTPROP $XRERR UNIQUE?
J 0
(-2415 2000);
DISPLAY 0.638298 (-2415 2000);
PAINT MONO (-2415 2000);
DISPLAY INVISIBLE (-2415 2000);
WIRE 16 -1 (-2175 1850)(-1125 1850);
FORCEPROP 2 LAST SIG_NAME TP_JUMPER_BLOCK_ 1_7
J 0
(-2125 1860);
DISPLAY 0.617021 (-2125 1860);
PAINT ORANGE (-2125 1860);
FORCEPROP 2 LASTPROP $XRERR UNIQUE?
J 0
(-2415 1850);
DISPLAY 0.638298 (-2415 1850);
PAINT MONO (-2415 1850);
DISPLAY INVISIBLE (-2415 1850);
WIRE 16 -1 (-2175 1950)(-1125 1950);
FORCEPROP 2 LAST SIG_NAME RST_BMC_SRST_N
J 0
(-2110 1960);
DISPLAY 0.617021 (-2110 1960);
PAINT ORANGE (-2110 1960);
WIRE 16 -1 (-2175 1800)(-1525 1800);
FORCEPROP 2 LAST SIG_NAME FM_CPLD_UART_CH_LOCK_N
J 0
(-2125 1810);
DISPLAY 0.617021 (-2125 1810);
PAINT ORANGE (-2125 1810);
WIRE 16 -1 (-1525 2150)(-1525 1800);
WIRE 16 -1 (-1525 1800)(-1125 1800);
WIRE 16 -1 (-1625 3425)(-1625 2825);
WIRE 16 -1 (-1050 3425)(-1050 2825);
WIRE 16 2175 (-5250 3900)(-2450 3900);
WIRE 16 2175 (-2450 3900)(-2450 5375);
WIRE 16 -1 (-4925 4500)(-3875 4500);
FORCEPROP 2 LAST SIG_NAME FM_PCH_SATA_RAID_KEY_R
J 0
(-4760 4510);
DISPLAY 0.617021 (-4760 4510);
PAINT ORANGE (-4760 4510);
FORCEPROP 2 LASTPROP $XRERR UNIQUE?
J 0
(-5000 4510);
DISPLAY 0.638298 (-5000 4510);
PAINT MONO (-5000 4510);
DISPLAY INVISIBLE (-5000 4510);
WIRE 16 -1 (-3875 4800)(-3875 4500);
WIRE 16 -1 (-3875 4500)(-3750 4500);
WIRE 16 -1 (-3075 4500)(-3550 4500);
FORCEPROP 2 LAST SIG_NAME FM_PCH_SATA_RAID_KEY
J 0
(-3510 4510);
DISPLAY 0.617021 (-3510 4510);
PAINT ORANGE (-3510 4510);
WIRE 16 -1 (-2150 4425)(-2150 4525);
WIRE 16 -1 (-2150 4525)(-1550 4525);
WIRE 16 -1 (-2150 4675)(-2150 4525);
WIRE 16 -1 (-25 4800)(-25 5075);
WIRE 16 -1 (-950 4800)(-25 4800);
WIRE 16 -1 (-25 5075)(-950 5075);
WIRE 16 -1 (-950 5075)(-950 4800);
WIRE 16 -1 (-900 4975)(-175 4975);
WIRE 16 -1 (-775 5050)(-775 4825);
WIRE 16 -1 (175 2775)(175 3450);
WIRE 16 -1 (-3275 2775)(175 2775);
WIRE 16 -1 (175 3450)(-3275 3450);
WIRE 16 -1 (-3275 3450)(-3275 2775);
WIRE 16 -1 (-3250 3325)(150 3325);
WIRE 16 -1 (-3250 3075)(150 3075);
WIRE 16 -1 (625 2000)(-425 2000);
FORCEPROP 2 LAST SIG_NAME TP_JUMPER_BLOCK_1_2
J 2
(600 2010);
DISPLAY 0.617021 (600 2010);
PAINT ORANGE (600 2010);
FORCEPROP 2 LASTPROP $XRERR UNIQUE?
J 0
(655 2000);
DISPLAY 0.638298 (655 2000);
PAINT MONO (655 2000);
DISPLAY INVISIBLE (655 2000);
WIRE 16 -1 (-425 1850)(625 1850);
FORCEPROP 2 LAST SIG_NAME TP_JUMPER_BLOCK_1_8
J 2
(600 1860);
DISPLAY 0.617021 (600 1860);
PAINT ORANGE (600 1860);
FORCEPROP 2 LASTPROP $XRERR UNIQUE?
J 0
(655 1850);
DISPLAY 0.638298 (655 1850);
PAINT MONO (655 1850);
DISPLAY INVISIBLE (655 1850);
WIRE 16 -1 (-425 1950)(-225 1950);
WIRE 16 -1 (625 1950)(-225 1950);
FORCEPROP 0 LAST SIG_NAME FM_IE_DISABLE_N
J 2
(600 1960);
DISPLAY 0.617021 (600 1960);
PAINT ORANGE (600 1960);
WIRE 16 -1 (-225 2150)(-225 1950);
WIRE 16 -1 (-425 1800)(200 1800);
WIRE 16 -1 (200 2125)(200 1800);
WIRE 16 -1 (200 1800)(625 1800);
FORCEPROP 2 LAST SIG_NAME FM_DIS_ADR_DLY
J 2
(600 1810);
DISPLAY 0.617021 (600 1810);
PAINT ORANGE (600 1810);
WIRE 16 2175 (-2350 3900)(275 3900);
WIRE 16 2175 (275 3900)(275 5350);
DOT 1 (-4850 4550);
DOT 1 (-1525 1800);
DOT 1 (-1250 1750);
DOT 1 (-300 1750);
DOT 1 (-225 1950);
DOT 1 (-3875 4500);
DOT 1 (-2150 4525);
DOT 1 (200 1800);
FORCENOTE
ROOM=SB
(-5229 717) 0;
DISPLAY LEFT (-5229 717);
DISPLAY 0.957447 (-5229 717);
PAINT PURPLE (-5229 717);
FORCENOTE
JUMPER LOCATION
(-3200 3350) 0;
DISPLAY LEFT (-3200 3350);
DISPLAY 1.021277 (-3200 3350);
PAINT PURPLE (-3200 3350);
FORCENOTE
1-3
(-2775 3225) 0;
DISPLAY LEFT (-2775 3225);
DISPLAY 1.021277 (-2775 3225);
PAINT PURPLE (-2775 3225);
FORCENOTE
7-9
(-2775 2975) 0;
DISPLAY LEFT (-2775 2975);
DISPLAY 1.021277 (-2775 2975);
PAINT PURPLE (-2775 2975);
FORCENOTE
3-5
(-2775 3100) 0;
DISPLAY LEFT (-2775 3100);
DISPLAY 1.021277 (-2775 3100);
PAINT PURPLE (-2775 3100);
FORCENOTE
9-11
(-2775 2850) 0;
DISPLAY LEFT (-2775 2850);
DISPLAY 1.021277 (-2775 2850);
PAINT PURPLE (-2775 2850);
FORCENOTE
NORMAL FUNCTIONALITY
(-2575 3225) 0;
DISPLAY LEFT (-2575 3225);
DISPLAY 1.021277 (-2575 3225);
PAINT PURPLE (-2575 3225);
FORCENOTE
BMC PINS SET TO HIGH IMPEDANCE
(-2575 3100) 0;
DISPLAY LEFT (-2575 3100);
DISPLAY 1.021277 (-2575 3100);
PAINT PURPLE (-2575 3100);
FORCENOTE
UART CHANNEL LOCKED
(-2575 2850) 0;
DISPLAY LEFT (-2575 2850);
DISPLAY 1.021277 (-2575 2850);
PAINT PURPLE (-2575 2850);
FORCENOTE
NORMAL FUNCTIONALITY
(-2575 2975) 0;
DISPLAY LEFT (-2575 2975);
DISPLAY 1.021277 (-2575 2975);
PAINT PURPLE (-2575 2975);
FORCENOTE
SYSTEM BEHAVIOR
(-2575 3350) 0;
DISPLAY LEFT (-2575 3350);
DISPLAY 1.021277 (-2575 3350);
PAINT PURPLE (-2575 3350);
FORCENOTE
8-10
(-1250 2975) 0;
DISPLAY LEFT (-1250 2975);
DISPLAY 1.021277 (-1250 2975);
PAINT PURPLE (-1250 2975);
FORCENOTE
2-4
(-1250 3225) 0;
DISPLAY LEFT (-1250 3225);
DISPLAY 1.021277 (-1250 3225);
PAINT PURPLE (-1250 3225);
FORCENOTE
4-6
(-1250 3100) 0;
DISPLAY LEFT (-1250 3100);
DISPLAY 1.021277 (-1250 3100);
PAINT PURPLE (-1250 3100);
FORCENOTE
10-12
(-1250 2850) 0;
DISPLAY LEFT (-1250 2850);
DISPLAY 1.021277 (-1250 2850);
PAINT PURPLE (-1250 2850);
FORCENOTE
JUMPER LOCATION
(-1600 3350) 0;
DISPLAY LEFT (-1600 3350);
DISPLAY 1.021277 (-1600 3350);
PAINT PURPLE (-1600 3350);
FORCENOTE
ADR DELAY DISABLED
(-950 2850) 0;
DISPLAY LEFT (-950 2850);
DISPLAY 1.021277 (-950 2850);
PAINT PURPLE (-950 2850);
FORCENOTE
SYSTEM BEHAVIOR
(-950 3350) 0;
DISPLAY LEFT (-950 3350);
DISPLAY 1.021277 (-950 3350);
PAINT PURPLE (-950 3350);
FORCENOTE
IE DISABLED
(-950 3100) 0;
DISPLAY LEFT (-950 3100);
DISPLAY 1.021277 (-950 3100);
PAINT PURPLE (-950 3100);
FORCENOTE
HIGH
(-900 5000) 0;
DISPLAY LEFT (-900 5000);
DISPLAY 0.617021 (-900 5000);
PAINT PURPLE (-900 5000);
FORCENOTE
LOW
(-900 4900) 0;
DISPLAY LEFT (-900 4900);
DISPLAY 0.617021 (-900 4900);
PAINT PURPLE (-900 4900);
FORCENOTE
ENABLE PCIE_UP[7:0]
(-700 4850) 0;
DISPLAY LEFT (-700 4850);
DISPLAY 0.617021 (-700 4850);
PAINT PURPLE (-700 4850);
FORCENOTE
DISABLE SATA
(-700 4900) 0;
DISPLAY LEFT (-700 4900);
DISPLAY 0.617021 (-700 4900);
PAINT PURPLE (-700 4900);
FORCENOTE
ENABLE SATA <DEFAULT>
(-700 5000) 0;
DISPLAY LEFT (-700 5000);
DISPLAY 0.617021 (-700 5000);
PAINT PURPLE (-700 5000);
FORCENOTE
NORMAL FUNCTIONALITY
(-950 2975) 0;
DISPLAY LEFT (-950 2975);
DISPLAY 1.021277 (-950 2975);
PAINT PURPLE (-950 2975);
FORCENOTE
NORMAL FUNCTIONALITY
(-950 3225) 0;
DISPLAY LEFT (-950 3225);
DISPLAY 1.021277 (-950 3225);
PAINT PURPLE (-950 3225);
QUIT
